;LEADER: 12 
;HEADER: 
;CODE  : ASCII 
;FILE  : 9324_DA0F0TMBIJ0_F0T_Motherboard_J_v01_20230324_0910-bd-18-6.drl for backdrilling ... from layer BOTTOM to layer GND2
;DESIGN: 9324_DA0F0TMBIJ0_F0T_Motherboard_J_v01_20230324_0910.brd
;MUST-NOT-CUT-LAYER = IN2,  MAX_DRILL_DEPTH = 72.25 MILS,  MFG_STUB_LENGTH = 0.00 MILS
;   BackdrillSize 1. = 15.700000 Tolerance = +0.000000/-0.000000 NON_PLATED MILS Quantity = 1320
;   BackdrillSize 2. = 17.700000 Tolerance = +0.000000/-0.000000 NON_PLATED MILS Quantity = 28
%
G90
X0141641Y0820341
X0125499Y0827034
X0141641Y0823688
X0125499Y0823688
X0141641Y0806955
X0141641Y0813648
X0125499Y0810302
X0125499Y0816995
X0141641Y0830381
X0141641Y0837074
X0125499Y0833727
X0125499Y0840420
X0141641Y0970932
X0125499Y0937467
X0141641Y0930774
X0125499Y0934121
X0141641Y0934121
X0141641Y0964239
X0125499Y0967585
X0111941Y0964239
X0095799Y0967585
X0141641Y0940814
X0141641Y0947507
X0125499Y0944160
X0125499Y0950853
X0141641Y0917389
X0141641Y0924081
X0125499Y0920735
X0125499Y0927428
X0125499Y0974278
X0141641Y0977625
X0125499Y0980971
X0141641Y0984318
X0125499Y0987664
X0141641Y0991011
X0125499Y0994357
X0125499Y1021129
X0141641Y1051247
X0125499Y1054593
X0111941Y1051247
X0095799Y1054593
X0125499Y1027822
X0141641Y1031168
X0125499Y1034515
X0141641Y1037861
X0125499Y1041207
X0141641Y1044554
X0125499Y1047900
X0141641Y1024475
X0111941Y1024475
X0141641Y1021129
X0111941Y1021129
X0141641Y1151641
X0125499Y1158333
X0141641Y1154987
X0125499Y1154987
X0141641Y1138255
X0141641Y1144948
X0125499Y1141601
X0125499Y1148294
X0141641Y1161680
X0141641Y1168373
X0125499Y1165026
X0125499Y1171719
X0141641Y1225263
X0125499Y1231955
X0141641Y1228609
X0125499Y1228609
X0141641Y1211877
X0141641Y1218570
X0125499Y1215223
X0125499Y1221916
X0141641Y1235302
X0141641Y1241995
X0125499Y1238648
X0125499Y1245341
X0201141Y1188452
X0184899Y1195144
X0201141Y1191799
X0184899Y1191798
X0184899Y1201837
X0184899Y1208530
X0184899Y1185105
X0201141Y1198491
X0201141Y1205184
X0201141Y1114830
X0184899Y1121522
X0201141Y1118177
X0184899Y1118176
X0201141Y1101444
X0201141Y1108137
X0184899Y1104790
X0184899Y1111483
X0201041Y1124869
X0201041Y1131562
X0184899Y1128215
X0184899Y1134908
X0201141Y1175066
X0201141Y1181759
X0184899Y1178412
X0201041Y0893963
X0184899Y0900656
X0201041Y0897310
X0184899Y0897310
X0201041Y0887270
X0184899Y0883924
X0184899Y0890617
X0201041Y0904003
X0201041Y0910696
X0184899Y0907349
X0184899Y0914042
X0184899Y0790223
X0201041Y0786877
X0184899Y0786877
X0201041Y0880577
X0201041Y0793570
X0201041Y0800263
X0184899Y0796916
X0184899Y0803609
X0201041Y0783530
X0201041Y0770144
X0201041Y0776837
X0184899Y0773491
X0184899Y0780184
X0369229Y0857789
X0367378Y0860993
X0361829Y0857789
X0359978Y0860993
X0354429Y0857789
X0352578Y0860993
X0371078Y0854584
X0365529Y0857789
X0363678Y0854584
X0358129Y0857789
X0356278Y0854584
X0350729Y0857789
X0343329Y0883423
X0335928Y0883423
X0341479Y0880219
X0337779Y0880219
X0371078Y0963530
X0363678Y0944304
X0371078Y0905853
X0371078Y0944304
X0363678Y0905853
X0359978Y0944304
X0367378Y0905853
X0367378Y0944304
X0359978Y0905853
X0367378Y0899445
X0369229Y0902649
X0363678Y0899445
X0361829Y0902649
X0369229Y0909057
X0367378Y0912262
X0361829Y0909057
X0363678Y0912262
X0367378Y0957122
X0369229Y0960326
X0363678Y0957122
X0361829Y0960326
X0369229Y0947509
X0367378Y0950713
X0361829Y0947509
X0363678Y0950713
X0367378Y0937896
X0369229Y0941100
X0363678Y0937896
X0361829Y0941100
X0359978Y0963530
X0369229Y0966735
X0361829Y0966735
X0367378Y0969939
X0363678Y0969939
X0345179Y0886627
X0371078Y0925079
X0337779Y0886627
X0363678Y0925079
X0341479Y0886627
X0367378Y0925079
X0334079Y0886627
X0359978Y0925079
X0367378Y0918670
X0369229Y0921875
X0363678Y0918670
X0361829Y0921875
X0369229Y0928283
X0367378Y0931488
X0343328Y0889832
X0341478Y0893036
X0335928Y0889832
X0337779Y0893036
X0361829Y0928283
X0363678Y0931488
X0369662Y0999684
X0371511Y1002888
X0362262Y0999684
X0367811Y1054157
X0364111Y1054157
X0371511Y1054157
X0360411Y1054157
X0367811Y1047749
X0369662Y1050952
X0364111Y1047749
X0362262Y1050952
X0369662Y1057361
X0367811Y1060565
X0362262Y1057361
X0364111Y1060565
X0369662Y1018910
X0367811Y1022114
X0362262Y1018910
X0364111Y1022114
X0364111Y1002888
X0367811Y1009297
X0364111Y1009297
X0369662Y1012501
X0362262Y1012501
X0371511Y1015705
X0360411Y1015705
X0367811Y1034931
X0367811Y1073383
X0364111Y1034931
X0364111Y1073383
X0371511Y1034931
X0371511Y1073383
X0360411Y1034931
X0360411Y1073383
X0362262Y1076587
X0364111Y1079791
X0367811Y1028523
X0369662Y1031727
X0364111Y1028523
X0362262Y1031727
X0369662Y1038136
X0367811Y1041340
X0362262Y1038136
X0364111Y1041340
X0367811Y1066974
X0369662Y1070178
X0364111Y1066974
X0362262Y1070178
X0369662Y1076587
X0367811Y1079791
X0371512Y1137469
X0367812Y1137469
X0364112Y1137469
X0360412Y1137469
X0356712Y1137469
X0351161Y1134264
X0369661Y1140973
X0365962Y1134264
X0362261Y1140973
X0358561Y1134264
X0349312Y1137469
X0371511Y1092608
X0364111Y1092608
X0367811Y1092608
X0360411Y1092608
X0367811Y1086200
X0369662Y1089404
X0364111Y1086200
X0362262Y1089404
X0369662Y1095813
X0367811Y1099017
X0362262Y1095813
X0364111Y1099017
X0386312Y1137469
X0382612Y1137469
X0378912Y1137469
X0375212Y1137469
X0408512Y1137469
X0404812Y1137469
X0401112Y1137469
X0397412Y1137469
X0393712Y1137469
X0390012Y1137469
X0388162Y1134264
X0384461Y1140973
X0380762Y1134264
X0377061Y1140973
X0373362Y1134264
X0410362Y1134264
X0406661Y1140973
X0402962Y1134264
X0399261Y1140973
X0395562Y1134264
X0391861Y1140973
X0384462Y1006093
X0377062Y1006093
X0380762Y1006093
X0373362Y1006093
X0441378Y0860993
X0446929Y0857789
X0448779Y0860993
X0454329Y0857789
X0456178Y0860993
X0461729Y0857789
X0463578Y0860993
X0469129Y0857789
X0470978Y0860993
X0443229Y0857789
X0445078Y0854584
X0450629Y0857789
X0452478Y0854584
X0458029Y0857789
X0459878Y0854584
X0465429Y0857789
X0467278Y0854584
X0385878Y0854584
X0382178Y0860993
X0376629Y0857789
X0374778Y0860993
X0435829Y0857789
X0432129Y0857789
X0428429Y0857789
X0426578Y0860993
X0421029Y0857789
X0419178Y0860993
X0413629Y0857789
X0411778Y0860993
X0406229Y0857789
X0404378Y0860993
X0398829Y0857789
X0396978Y0860993
X0391429Y0857789
X0389578Y0860993
X0384029Y0857789
X0380329Y0857789
X0378478Y0854584
X0372929Y0857789
X0437679Y0854584
X0433979Y0860993
X0430278Y0854584
X0424729Y0857789
X0422878Y0854584
X0417329Y0857789
X0415478Y0854584
X0409929Y0857789
X0408078Y0854584
X0402529Y0857789
X0400678Y0854584
X0395129Y0857789
X0393278Y0854584
X0387729Y0857789
X0493178Y0860993
X0496878Y0854584
X0502429Y0857789
X0504278Y0854584
X0507978Y0860993
X0511678Y0854584
X0515378Y0860993
X0519078Y0854584
X0524629Y0857789
X0476529Y0857789
X0478378Y0860993
X0483929Y0857789
X0485778Y0860993
X0491329Y0857789
X0526478Y0854584
X0495029Y0857789
X0498729Y0857789
X0500578Y0860993
X0506129Y0857789
X0509829Y0857789
X0513529Y0857789
X0517229Y0857789
X0520929Y0857789
X0522778Y0860993
X0472829Y0857789
X0474678Y0854584
X0480229Y0857789
X0482078Y0854584
X0487629Y0857789
X0489478Y0854584
X0528329Y0857789
X0520929Y0973143
X0509829Y0953917
X0517229Y0915466
X0517229Y0953917
X0509829Y0915466
X0513529Y0953917
X0520929Y0915466
X0520929Y0953917
X0513529Y0915466
X0517229Y0909057
X0519078Y0912262
X0513529Y0909057
X0511678Y0912262
X0519078Y0918670
X0517229Y0921875
X0511678Y0918670
X0513529Y0921875
X0513529Y0966735
X0511678Y0969939
X0517229Y0966735
X0519078Y0969939
X0519078Y0957122
X0517229Y0960326
X0511678Y0957122
X0513529Y0960326
X0517229Y0947509
X0519078Y0950713
X0513529Y0947509
X0511678Y0950713
X0509829Y0973143
X0519078Y0976347
X0511678Y0976347
X0517229Y0979552
X0513529Y0979552
X0506129Y0979552
X0504278Y0976347
X0500578Y0976347
X0498729Y0979552
X0496878Y0982756
X0504278Y0982756
X0500578Y0982756
X0507978Y0982756
X0520929Y0896240
X0517229Y0934691
X0513529Y0896240
X0509829Y0934691
X0517229Y0896240
X0520929Y0934691
X0509829Y0896240
X0513529Y0934691
X0517229Y0928283
X0519078Y0931488
X0513529Y0928283
X0511678Y0931488
X0519078Y0937896
X0507978Y0893036
X0522778Y0893036
X0517229Y0941100
X0511678Y0893036
X0519078Y0893036
X0519078Y0899445
X0517229Y0902649
X0511678Y0899445
X0513529Y0902649
X0511678Y0937896
X0513529Y0941100
X0517662Y1044544
X0517662Y1082995
X0513962Y1044544
X0510262Y1082995
X0521362Y1044544
X0521362Y1082995
X0510262Y1044544
X0513962Y1082995
X0517662Y1076587
X0519511Y1079791
X0513962Y1076587
X0512111Y1079791
X0517662Y1038136
X0519511Y1041340
X0513962Y1038136
X0512111Y1041340
X0519511Y1047749
X0517662Y1050952
X0512111Y1047749
X0513962Y1050952
X0499162Y1018910
X0501011Y1022114
X0506562Y1018910
X0504711Y1022114
X0504711Y1009297
X0501011Y1009297
X0506562Y1012501
X0499162Y1012501
X0508411Y1015705
X0497311Y1015705
X0517662Y1025318
X0517662Y1063770
X0510262Y1025318
X0513962Y1063770
X0521362Y1025318
X0521362Y1063770
X0513962Y1025318
X0510262Y1063770
X0512111Y1066974
X0513962Y1070178
X0517662Y1018910
X0519511Y1022114
X0513962Y1018910
X0512111Y1022114
X0519511Y1028523
X0517662Y1031727
X0512111Y1028523
X0513962Y1031727
X0517662Y1057361
X0519511Y1060565
X0513962Y1057361
X0512111Y1060565
X0519511Y1066974
X0517662Y1070178
X0497312Y1137469
X0499162Y1134264
X0502861Y1140973
X0508412Y1137469
X0510261Y1140973
X0515812Y1137469
X0519512Y1137469
X0521362Y1134264
X0526912Y1137469
X0473261Y1140973
X0478812Y1137469
X0480661Y1140973
X0486212Y1137469
X0489912Y1137469
X0491762Y1134264
X0534312Y1137469
X0495461Y1140973
X0501012Y1137469
X0504712Y1137469
X0506562Y1134264
X0512112Y1137469
X0513962Y1134264
X0517661Y1140973
X0523212Y1137469
X0525061Y1140973
X0475112Y1137469
X0476962Y1134264
X0482512Y1137469
X0484362Y1134264
X0488061Y1140973
X0493612Y1137469
X0532462Y1134264
X0519511Y1086200
X0517662Y1089404
X0512111Y1086200
X0513962Y1089404
X0696441Y0783530
X0696441Y0770144
X0696441Y0776837
X0680299Y0773491
X0680299Y0780184
X0755841Y0820341
X0739699Y0827034
X0755841Y0823688
X0739699Y0823688
X0755841Y0806955
X0755841Y0813648
X0739699Y0810302
X0739699Y0816995
X0755841Y0830381
X0755841Y0837074
X0739699Y0833727
X0739699Y0840420
X0680299Y0790223
X0696441Y0786877
X0680299Y0786877
X0696441Y0880577
X0696441Y0793570
X0696441Y0800263
X0680299Y0796916
X0680299Y0803609
X0755741Y0970932
X0739699Y0937467
X0755841Y0930774
X0739699Y0934121
X0755841Y0934121
X0755841Y0964239
X0739699Y0967585
X0769399Y0967585
X0755841Y0940814
X0755841Y0947507
X0739699Y0944160
X0739699Y0950853
X0755841Y0917389
X0755841Y0924081
X0739699Y0920735
X0739699Y0927428
X0739699Y0974278
X0755841Y0977625
X0739699Y0980971
X0696441Y0893963
X0680299Y0900656
X0696441Y0897310
X0680299Y0897310
X0696441Y0887270
X0680299Y0883924
X0680299Y0890617
X0696441Y0904003
X0696441Y0910696
X0680299Y0907349
X0680299Y0914042
X0755841Y0984318
X0739699Y0987664
X0755841Y0991011
X0739699Y0994357
X0739699Y1021129
X0755841Y1051247
X0739699Y1054593
X0769399Y1054593
X0739699Y1027822
X0755841Y1031168
X0739699Y1034514
X0755541Y1037861
X0739699Y1041207
X0755541Y1044554
X0739699Y1047900
X0755841Y1024475
X0755841Y1021129
X0755841Y1151640
X0739699Y1158333
X0755841Y1154987
X0739699Y1154987
X0755841Y1138255
X0755841Y1144947
X0739699Y1141601
X0739699Y1148294
X0755841Y1161680
X0755841Y1168373
X0739699Y1165026
X0739699Y1171719
X0696441Y1114829
X0680299Y1121522
X0696441Y1118176
X0680299Y1118176
X0696441Y1101444
X0696441Y1108136
X0680299Y1104790
X0680299Y1111483
X0696441Y1124869
X0696441Y1131562
X0680299Y1128215
X0680299Y1134908
X0696441Y1175066
X0696441Y1181758
X0680299Y1178412
X0755841Y1225262
X0739699Y1231955
X0755841Y1228609
X0739699Y1228609
X0755841Y1211877
X0755841Y1218569
X0739699Y1215223
X0739699Y1221916
X0755841Y1235302
X0755841Y1241995
X0739699Y1238648
X0739699Y1245341
X0696441Y1188451
X0680299Y1195144
X0696441Y1191798
X0680299Y1191798
X0680299Y1201837
X0680299Y1208530
X0680299Y1185105
X0696441Y1198491
X0696441Y1205184
X0785541Y1051247
X0785541Y1024475
X0785541Y1021129
X0785541Y0964239
X1161041Y0773491
X1161041Y0780184
X1117783Y0820341
X1101641Y0827034
X1117783Y0823688
X1101641Y0823688
X1117783Y0806955
X1117783Y0813648
X1101641Y0810302
X1101641Y0816995
X1117783Y0830381
X1117783Y0837074
X1101641Y0833727
X1101641Y0840420
X1161041Y0790223
X1161041Y0786877
X1161041Y0796916
X1161041Y0803609
X1117783Y0970932
X1101641Y0937467
X1117783Y0930774
X1101641Y0934121
X1117783Y0934121
X1117783Y0964239
X1101641Y0967585
X1088083Y0964239
X1071941Y0967585
X1117783Y0940814
X1117783Y0947507
X1101641Y0944160
X1101641Y0950853
X1117783Y0917389
X1117783Y0924081
X1101641Y0920735
X1101641Y0927428
X1101641Y0974278
X1117783Y0977625
X1101641Y0980971
X1161041Y0900656
X1161041Y0897310
X1161041Y0883924
X1161041Y0890617
X1161041Y0907349
X1161041Y0914042
X1117783Y0984318
X1101641Y0987664
X1117783Y0991011
X1101641Y0994357
X1101641Y1021129
X1117783Y1051247
X1101641Y1054593
X1088083Y1051247
X1071941Y1054593
X1101641Y1027822
X1117783Y1031168
X1101641Y1034515
X1117783Y1037861
X1101641Y1041207
X1117783Y1044554
X1101641Y1047900
X1117783Y1024475
X1088083Y1024475
X1117783Y1021129
X1088083Y1021129
X1117783Y1151641
X1101641Y1158333
X1117783Y1154987
X1101641Y1154987
X1117783Y1138255
X1117783Y1144948
X1101641Y1141601
X1101641Y1148294
X1117783Y1161680
X1117783Y1168373
X1101641Y1165026
X1101641Y1171719
X1161041Y1121522
X1161041Y1118176
X1161041Y1104790
X1161041Y1111483
X1161041Y1128215
X1161041Y1134908
X1161041Y1178412
X1117783Y1225263
X1101641Y1231955
X1117783Y1228609
X1101641Y1228609
X1117783Y1211877
X1117783Y1218570
X1101641Y1215223
X1101641Y1221916
X1117783Y1235302
X1117783Y1241995
X1101641Y1238648
X1101641Y1245341
X1161041Y1195144
X1161041Y1191798
X1161041Y1201837
X1161041Y1208530
X1161041Y1185105
X1177283Y1188452
X1177283Y1191799
X1177283Y1198491
X1177283Y1205184
X1177283Y1114830
X1177283Y1118177
X1177283Y1101444
X1177283Y1108137
X1177183Y1124869
X1177183Y1131562
X1177283Y1175066
X1177283Y1181759
X1177183Y0893963
X1177183Y0897310
X1177183Y0887270
X1177183Y0904003
X1177183Y0910696
X1177183Y0786877
X1177183Y0880577
X1177183Y0793570
X1177183Y0800263
X1177183Y0783530
X1177183Y0770144
X1177183Y0776837
X1352557Y0183348
X1355761Y0181498
X1346137Y0179649
X1355761Y0174098
X1349351Y0181498
X1352557Y0175948
X1349351Y0185198
X1355761Y0185198
X1362020Y0854584
X1358320Y0860993
X1352771Y0857789
X1350920Y0860993
X1347220Y0854584
X1343520Y0860993
X1339820Y0854584
X1336120Y0860993
X1330571Y0857789
X1371271Y0857789
X1369420Y0854584
X1363871Y0857789
X1328720Y0860993
X1360171Y0857789
X1356471Y0857789
X1354620Y0854584
X1349071Y0857789
X1345371Y0857789
X1341671Y0857789
X1337971Y0857789
X1334271Y0857789
X1332420Y0854584
X1367571Y0857789
X1365720Y0860993
X1326871Y0857789
X1319471Y0883423
X1312070Y0883423
X1317621Y0880219
X1313921Y0880219
X1347220Y0963530
X1339820Y0944304
X1347220Y0905853
X1347220Y0944304
X1339820Y0905853
X1336120Y0944304
X1343520Y0905853
X1343520Y0944304
X1336120Y0905853
X1343520Y0899445
X1345371Y0902649
X1339820Y0899445
X1337971Y0902649
X1345371Y0909057
X1343520Y0912262
X1337971Y0909057
X1339820Y0912262
X1343520Y0957122
X1345371Y0960326
X1339820Y0957122
X1337971Y0960326
X1345371Y0947509
X1343520Y0950713
X1337971Y0947509
X1339820Y0950713
X1343520Y0937896
X1345371Y0941100
X1339820Y0937896
X1337971Y0941100
X1336120Y0963530
X1345371Y0966735
X1337971Y0966735
X1343520Y0969939
X1339820Y0969939
X1321321Y0886627
X1347220Y0925079
X1313921Y0886627
X1339820Y0925079
X1317621Y0886627
X1343520Y0925079
X1310221Y0886627
X1336120Y0925079
X1343520Y0918670
X1345371Y0921875
X1339820Y0918670
X1337971Y0921875
X1345371Y0928283
X1343520Y0931488
X1319470Y0889832
X1317620Y0893036
X1312070Y0889832
X1313921Y0893036
X1337971Y0928283
X1339820Y0931488
X1345804Y0999684
X1347653Y1002888
X1338404Y0999684
X1343953Y1054157
X1340253Y1054157
X1347653Y1054157
X1336553Y1054157
X1343953Y1047749
X1345804Y1050952
X1340253Y1047749
X1338404Y1050952
X1345804Y1057361
X1343953Y1060565
X1338404Y1057361
X1340253Y1060565
X1345804Y1018910
X1343953Y1022114
X1338404Y1018910
X1340253Y1022114
X1340253Y1002888
X1343953Y1009297
X1340253Y1009297
X1345804Y1012501
X1338404Y1012501
X1347653Y1015705
X1336553Y1015705
X1360604Y1006093
X1353204Y1006093
X1356904Y1006093
X1349504Y1006093
X1343953Y1034931
X1343953Y1073383
X1340253Y1034931
X1340253Y1073383
X1347653Y1034931
X1347653Y1073383
X1336553Y1034931
X1336553Y1073383
X1338404Y1076587
X1340253Y1079791
X1343953Y1028523
X1345804Y1031727
X1340253Y1028523
X1338404Y1031727
X1345804Y1038136
X1343953Y1041340
X1338404Y1038136
X1340253Y1041340
X1343953Y1066974
X1345804Y1070178
X1340253Y1066974
X1338404Y1070178
X1345804Y1076587
X1343953Y1079791
X1362454Y1137469
X1358754Y1137469
X1355054Y1137469
X1351354Y1137469
X1347654Y1137469
X1343954Y1137469
X1340254Y1137469
X1336554Y1137469
X1332854Y1137469
X1369854Y1137469
X1366154Y1137469
X1327303Y1134264
X1364304Y1134264
X1360603Y1140973
X1356904Y1134264
X1353203Y1140973
X1349504Y1134264
X1345803Y1140973
X1342104Y1134264
X1338403Y1140973
X1334703Y1134264
X1371704Y1134264
X1368003Y1140973
X1325452Y1137469
X1347653Y1092608
X1340253Y1092608
X1343953Y1092608
X1336553Y1092608
X1343953Y1086200
X1345804Y1089404
X1340253Y1086200
X1338404Y1089404
X1345804Y1095813
X1343953Y1099017
X1338404Y1095813
X1340253Y1099017
X1384654Y1137469
X1380954Y1137469
X1377254Y1137469
X1373554Y1137469
X1386504Y1134264
X1382803Y1140973
X1379104Y1134264
X1375403Y1140973
X1449403Y1140973
X1454954Y1137469
X1456803Y1140973
X1462354Y1137469
X1466054Y1137469
X1467904Y1134264
X1471603Y1140973
X1451254Y1137469
X1453104Y1134264
X1458654Y1137469
X1460504Y1134264
X1464203Y1140973
X1469754Y1137469
X1413821Y0854584
X1408271Y0857789
X1406420Y0854584
X1400871Y0857789
X1399020Y0854584
X1393471Y0857789
X1391620Y0854584
X1386071Y0857789
X1384220Y0854584
X1378671Y0857789
X1376820Y0854584
X1411971Y0857789
X1410121Y0860993
X1404571Y0857789
X1402720Y0860993
X1397171Y0857789
X1395320Y0860993
X1389771Y0857789
X1387920Y0860993
X1382371Y0857789
X1380520Y0860993
X1374971Y0857789
X1373120Y0860993
X1469320Y0860993
X1419371Y0857789
X1423071Y0857789
X1426771Y0857789
X1428620Y0854584
X1434171Y0857789
X1436020Y0854584
X1441571Y0857789
X1443420Y0854584
X1448971Y0857789
X1450820Y0854584
X1456371Y0857789
X1458220Y0854584
X1463771Y0857789
X1465620Y0854584
X1471171Y0857789
X1417520Y0860993
X1421220Y0854584
X1424921Y0860993
X1430471Y0857789
X1432320Y0860993
X1437871Y0857789
X1439720Y0860993
X1445271Y0857789
X1447120Y0860993
X1452671Y0857789
X1454520Y0860993
X1460071Y0857789
X1461920Y0860993
X1467471Y0857789
X1473020Y0854584
X1478571Y0857789
X1480420Y0854584
X1485971Y0857789
X1487820Y0854584
X1493371Y0857789
X1495220Y0854584
X1500771Y0857789
X1502620Y0854584
X1474871Y0857789
X1476720Y0860993
X1482271Y0857789
X1484120Y0860993
X1489671Y0857789
X1491520Y0860993
X1497071Y0857789
X1498920Y0860993
X1504471Y0857789
X1497071Y0973143
X1485971Y0953917
X1493371Y0915466
X1493371Y0953917
X1485971Y0915466
X1489671Y0953917
X1497071Y0915466
X1497071Y0953917
X1489671Y0915466
X1493371Y0909057
X1495220Y0912262
X1489671Y0909057
X1487820Y0912262
X1495220Y0918670
X1493371Y0921875
X1487820Y0918670
X1489671Y0921875
X1489671Y0966735
X1487820Y0969939
X1493371Y0966735
X1495220Y0969939
X1495220Y0957122
X1493371Y0960326
X1487820Y0957122
X1489671Y0960326
X1493371Y0947509
X1495220Y0950713
X1489671Y0947509
X1487820Y0950713
X1485971Y0973143
X1495220Y0976347
X1487820Y0976347
X1493371Y0979552
X1489671Y0979552
X1482271Y0979552
X1480420Y0976347
X1476720Y0976347
X1474871Y0979552
X1473020Y0982756
X1480420Y0982756
X1476720Y0982756
X1484120Y0982756
X1497071Y0896240
X1493371Y0934691
X1489671Y0896240
X1485971Y0934691
X1493371Y0896240
X1497071Y0934691
X1485971Y0896240
X1489671Y0934691
X1493371Y0928283
X1495220Y0931488
X1489671Y0928283
X1487820Y0931488
X1495220Y0937896
X1484120Y0893036
X1498920Y0893036
X1493371Y0941100
X1487820Y0893036
X1495220Y0893036
X1495220Y0899445
X1493371Y0902649
X1487820Y0899445
X1489671Y0902649
X1487820Y0937896
X1489671Y0941100
X1493804Y1044544
X1493804Y1082995
X1490104Y1044544
X1486404Y1082995
X1497504Y1044544
X1497504Y1082995
X1486404Y1044544
X1490104Y1082995
X1493804Y1076587
X1495653Y1079791
X1490104Y1076587
X1488253Y1079791
X1493804Y1038136
X1495653Y1041340
X1490104Y1038136
X1488253Y1041340
X1495653Y1047749
X1493804Y1050952
X1488253Y1047749
X1490104Y1050952
X1475304Y1018910
X1477153Y1022114
X1482704Y1018910
X1480853Y1022114
X1480853Y1009297
X1477153Y1009297
X1482704Y1012501
X1475304Y1012501
X1484553Y1015705
X1473453Y1015705
X1493804Y1025318
X1493804Y1063770
X1486404Y1025318
X1490104Y1063770
X1497504Y1025318
X1497504Y1063770
X1490104Y1025318
X1486404Y1063770
X1488253Y1066974
X1490104Y1070178
X1493804Y1018910
X1495653Y1022114
X1490104Y1018910
X1488253Y1022114
X1495653Y1028523
X1493804Y1031727
X1488253Y1028523
X1490104Y1031727
X1493804Y1057361
X1495653Y1060565
X1490104Y1057361
X1488253Y1060565
X1495653Y1066974
X1493804Y1070178
X1473454Y1137469
X1475304Y1134264
X1479003Y1140973
X1484554Y1137469
X1486403Y1140973
X1491954Y1137469
X1495654Y1137469
X1497504Y1134264
X1503054Y1137469
X1510454Y1137469
X1477154Y1137469
X1480854Y1137469
X1482704Y1134264
X1488254Y1137469
X1490104Y1134264
X1493803Y1140973
X1499354Y1137469
X1501203Y1140973
X1508604Y1134264
X1495653Y1086200
X1493804Y1089404
X1488253Y1086200
X1490104Y1089404
X1656441Y1195144
X1656441Y1191798
X1656441Y1201837
X1656441Y1208530
X1656441Y1185105
X1656441Y1121522
X1656441Y1118176
X1656441Y1104790
X1656441Y1111483
X1656441Y1128215
X1656441Y1134908
X1656441Y1178412
X1656441Y0900656
X1656441Y0897310
X1656441Y0883924
X1656441Y0890617
X1656441Y0907349
X1656441Y0914042
X1656441Y0790223
X1656441Y0786877
X1656441Y0796916
X1656441Y0803609
X1656441Y0773491
X1656441Y0780184
X1672583Y0783530
X1672583Y0770144
X1672583Y0776837
X1731983Y0820341
X1715841Y0827034
X1731983Y0823688
X1715841Y0823688
X1731983Y0806955
X1731983Y0813648
X1715841Y0810302
X1715841Y0816995
X1731983Y0830381
X1731983Y0837074
X1715841Y0833727
X1715841Y0840420
X1672583Y0786877
X1672583Y0880577
X1672583Y0793570
X1672583Y0800263
X1731883Y0970932
X1715841Y0937467
X1731983Y0930774
X1715841Y0934121
X1731983Y0934121
X1731983Y0964239
X1715841Y0967585
X1761683Y0964239
X1745541Y0967585
X1731983Y0940814
X1731983Y0947507
X1715841Y0944160
X1715841Y0950853
X1731983Y0917389
X1731983Y0924081
X1715841Y0920735
X1715841Y0927428
X1715841Y0974278
X1731983Y0977625
X1715841Y0980971
X1672583Y0893963
X1672583Y0897310
X1672583Y0887270
X1672583Y0904003
X1672583Y0910696
X1731983Y0984318
X1715841Y0987664
X1731983Y0991011
X1715841Y0994357
X1715841Y1021129
X1731983Y1051247
X1715841Y1054593
X1761683Y1051247
X1745541Y1054593
X1715841Y1027822
X1731983Y1031168
X1715841Y1034514
X1731683Y1037861
X1715841Y1041207
X1731683Y1044554
X1715841Y1047900
X1731983Y1024475
X1761683Y1024475
X1731983Y1021129
X1761683Y1021129
X1731983Y1151640
X1715841Y1158333
X1731983Y1154987
X1715841Y1154987
X1731983Y1138255
X1731983Y1144947
X1715841Y1141601
X1715841Y1148294
X1731983Y1161680
X1731983Y1168373
X1715841Y1165026
X1715841Y1171719
X1672583Y1114829
X1672583Y1118176
X1672583Y1101444
X1672583Y1108136
X1672583Y1124869
X1672583Y1131562
X1672583Y1175066
X1672583Y1181758
X1731983Y1225262
X1715841Y1231955
X1731983Y1228609
X1715841Y1228609
X1731983Y1211877
X1731983Y1218569
X1715841Y1215223
X1715841Y1221916
X1731983Y1235302
X1731983Y1241995
X1715841Y1238648
X1715841Y1245341
X1672583Y1188451
X1672583Y1191798
X1672583Y1198491
X1672583Y1205184
M00
X0064870Y0084622
X0061470Y0084622
X0078120Y1518836
X0078120Y1515436
X0090998Y1515537
X0090998Y1518937
X0523142Y0071436
X0519742Y0071436
X0523164Y0040328
X0519764Y0040328
X0947496Y0229535
X0957156Y0230563
X0947496Y0211997
X0953970Y0204875
X0947496Y0226135
X0957156Y0227163
X0947496Y0215397
X0953970Y0208275
X1032433Y-0019811
X1032433Y-0023211
X1341752Y-0023211
X1341752Y-0019811
X1290291Y-0019811
X1290291Y-0023211
X1412284Y0171696
X1415684Y0171696
X1482650Y-0023211
X1482650Y-0019811
M30
